# T6G (Grand Teton) — schematic netlist excerpt (pin names and nets, part order shuffled) for the footprints in the layout excerpt that follows; sources: Cadence DE-HDL packaged netlist, KiCad conversion of 04192023_DAF0TMB3IC0_F0TG_MB_C_brd_V02_OCP.brd

R6825  Q_RES  0 5% CHIP  pkg 0402LF  page 81 : A = RST_RT_CPU0_P3_PERST_R2_N ; B = RST_RT_CPU0_P3_PERST_R_N
C7502  Q_CAP  0.1UF 10V 10% X7S  pkg C0201  page 333 : A = P1V8_CPU1_RT_1D ; B = GND
R2113  Q_RES  0 5% CHIP  pkg 0402LF  page 144 : A = RST_PERST_BUF_M2_0_N ; B = RST_PERST_BUF_M2_0_R_N

(kicad_pcb
	(version 20260206)
	(generator "pcbnew")
	(generator_version "10.0")
	(general
		(thickness 1.6)
		(legacy_teardrops no)
	)
	(paper "A4")
	(title_block
		(title "04192023_DAF0TMB3IC0_F0TG_MB_C_brd_V02_OCP.brd")
		(comment 1 "Grand Teton / footprints 1237-1239 of 8354")
	)
	(layers
		(0 "F.Cu" signal "TOP")
		(4 "In1.Cu" signal "GND")
		(6 "In2.Cu" signal "IN1")
		(8 "In3.Cu" signal "GND1")
		(10 "In4.Cu" signal "IN2")
		(12 "In5.Cu" signal "GND2")
		(14 "In6.Cu" signal "IN3")
		(16 "In7.Cu" signal "GND3")
		(18 "In8.Cu" signal "VCC")
		(20 "In9.Cu" signal "VCC1")
		(22 "In10.Cu" signal "GND4")
		(24 "In11.Cu" signal "IN4")
		(26 "In12.Cu" signal "GND5")
		(28 "In13.Cu" signal "IN5")
		(30 "In14.Cu" signal "GND6")
		(32 "In15.Cu" signal "IN6")
		(34 "In16.Cu" signal "GND7")
		(2 "B.Cu" signal "BOTTOM")
		(9 "F.Adhes" user "F.Adhesive")
		(11 "B.Adhes" user "B.Adhesive")
		(13 "F.Paste" user "Package Geometry/Pastemask Top")
		(15 "B.Paste" user "Package Geometry/Pastemask Bottom")
		(5 "F.SilkS" user "Ref Des/Silkscreen Top")
		(7 "B.SilkS" user "Ref Des/Silkscreen Bottom")
		(1 "F.Mask" user "Board Geometry/Soldermask Top")
		(3 "B.Mask" user "Board Geometry/Soldermask Bottom")
		(17 "Dwgs.User" user "User.Drawings")
		(19 "Cmts.User" user "User.Comments")
		(21 "Eco1.User" user "User.Eco1")
		(23 "Eco2.User" user "User.Eco2")
		(25 "Edge.Cuts" user "Board Geometry/Outline")
		(27 "Margin" user)
		(31 "F.CrtYd" user "Package Geometry/Place Bound Top")
		(29 "B.CrtYd" user "Package Geometry/Place Bound Bottom")
		(35 "F.Fab" user "Ref Des/Assembly Top")
		(33 "B.Fab" user "Ref Des/Assembly Bottom")
	)
	(footprint ""
		(layer "F.Cu")
		(at 110.644432 -397.232378 180)
		(property "Reference" "C7502"
			(at 0 0 180)
			(layer "F.SilkS")
			(hide yes)
			(effects
				(font
					(size 1.27 1.27)
				)
			)
		)
		(property "Value" ""
			(at 0 0 180)
			(layer "F.Fab")
			(effects
				(font
					(size 1.27 1.27)
				)
			)
		)
		(duplicate_pad_numbers_are_jumpers no)
		(fp_line
			(start 0.299974 0.150114)
			(end -0.299974 0.150114)
			(stroke
				(width 0.1)
				(type default)
			)
			(layer "F.Fab")
		)
		(fp_line
			(start 0.299974 -0.150114)
			(end 0.299974 0.150114)
			(stroke
				(width 0.1)
				(type default)
			)
			(layer "F.Fab")
		)
		(fp_line
			(start -0.299974 0.150114)
			(end -0.299974 -0.150114)
			(stroke
				(width 0.1)
				(type default)
			)
			(layer "F.Fab")
		)
		(fp_line
			(start -0.299974 -0.150114)
			(end 0.299974 -0.150114)
			(stroke
				(width 0.1)
				(type default)
			)
			(layer "F.Fab")
		)
		(pad "1" smd rect
			(at -0.2667 0 180)
			(size 0.3048 0.381)
			(layers "F.Cu" "F.Mask" "F.Paste")
			(net "P1V8_CPU1_RT_1D")
		)
		(pad "2" smd rect
			(at 0.2667 0 180)
			(size 0.3048 0.381)
			(layers "F.Cu" "F.Mask" "F.Paste")
			(net "GND")
		)
	)
	(footprint ""
		(layer "F.Cu")
		(at 140.886942 -102.510844 180)
		(property "Reference" "R2113"
			(at 0 0 180)
			(layer "F.SilkS")
			(hide yes)
			(effects
				(font
					(size 1.27 1.27)
				)
			)
		)
		(property "Value" ""
			(at 0 0 180)
			(layer "F.Fab")
			(effects
				(font
					(size 1.27 1.27)
				)
			)
		)
		(duplicate_pad_numbers_are_jumpers no)
		(fp_line
			(start 0.7874 0.4064)
			(end -0.7874 0.4064)
			(stroke
				(width 0.1524)
				(type default)
			)
			(layer "F.SilkS")
		)
		(fp_line
			(start 0.7874 -0.4064)
			(end 0.7874 0.4064)
			(stroke
				(width 0.1524)
				(type default)
			)
			(layer "F.SilkS")
		)
		(fp_line
			(start -0.7874 0.4064)
			(end -0.7874 -0.4064)
			(stroke
				(width 0.1524)
				(type default)
			)
			(layer "F.SilkS")
		)
		(fp_line
			(start -0.7874 -0.4064)
			(end 0.7874 -0.4064)
			(stroke
				(width 0.1524)
				(type default)
			)
			(layer "F.SilkS")
		)
		(fp_line
			(start 0.67945 0.3048)
			(end 0.120396 0.3048)
			(stroke
				(width 0.1)
				(type default)
			)
			(layer "F.Fab")
		)
		(fp_line
			(start 0.67945 -0.3048)
			(end 0.67945 0.3048)
			(stroke
				(width 0.1)
				(type default)
			)
			(layer "F.Fab")
		)
		(fp_line
			(start 0.12065 -0.2794)
			(end 0.12065 -0.3048)
			(stroke
				(width 0.1)
				(type default)
			)
			(layer "F.Fab")
		)
		(fp_line
			(start 0.12065 -0.3048)
			(end 0.67945 -0.3048)
			(stroke
				(width 0.1)
				(type default)
			)
			(layer "F.Fab")
		)
		(fp_line
			(start 0.120396 0.3048)
			(end 0.120396 0.2794)
			(stroke
				(width 0.1)
				(type default)
			)
			(layer "F.Fab")
		)
		(fp_line
			(start 0.120396 0.2794)
			(end -0.12065 0.2794)
			(stroke
				(width 0.1)
				(type default)
			)
			(layer "F.Fab")
		)
		(fp_line
			(start -0.12065 0.3048)
			(end -0.67945 0.3048)
			(stroke
				(width 0.1)
				(type default)
			)
			(layer "F.Fab")
		)
		(fp_line
			(start -0.12065 0.2794)
			(end -0.12065 0.3048)
			(stroke
				(width 0.1)
				(type default)
			)
			(layer "F.Fab")
		)
		(fp_line
			(start -0.12065 -0.2794)
			(end 0.12065 -0.2794)
			(stroke
				(width 0.1)
				(type default)
			)
			(layer "F.Fab")
		)
		(fp_line
			(start -0.12065 -0.305054)
			(end -0.12065 -0.2794)
			(stroke
				(width 0.1)
				(type default)
			)
			(layer "F.Fab")
		)
		(fp_line
			(start -0.67945 0.3048)
			(end -0.67945 -0.305054)
			(stroke
				(width 0.1)
				(type default)
			)
			(layer "F.Fab")
		)
		(fp_line
			(start -0.67945 -0.305054)
			(end -0.12065 -0.305054)
			(stroke
				(width 0.1)
				(type default)
			)
			(layer "F.Fab")
		)
		(pad "1" smd circle
			(at -0.40005 0 180)
			(size 0 0)
			(layers "F.Cu" "F.Mask" "F.Paste")
			(net "RST_PERST_BUF_M2_0_N")
		)
		(pad "2" smd circle
			(at 0.40005 0 180)
			(size 0 0)
			(layers "F.Cu" "F.Mask" "F.Paste")
			(net "RST_PERST_BUF_M2_0_R_N")
		)
	)
	(footprint ""
		(layer "F.Cu")
		(at 216.99855 -127.801116)
		(property "Reference" "R6825"
			(at 0 0 0)
			(layer "F.SilkS")
			(hide yes)
			(effects
				(font
					(size 1.27 1.27)
				)
			)
		)
		(property "Value" ""
			(at 0 0 0)
			(layer "F.Fab")
			(effects
				(font
					(size 1.27 1.27)
				)
			)
		)
		(duplicate_pad_numbers_are_jumpers no)
		(fp_line
			(start -0.7874 -0.4064)
			(end 0.7874 -0.4064)
			(stroke
				(width 0.1524)
				(type default)
			)
			(layer "F.SilkS")
		)
		(fp_line
			(start -0.7874 0.4064)
			(end -0.7874 -0.4064)
			(stroke
				(width 0.1524)
				(type default)
			)
			(layer "F.SilkS")
		)
		(fp_line
			(start 0.7874 -0.4064)
			(end 0.7874 0.4064)
			(stroke
				(width 0.1524)
				(type default)
			)
			(layer "F.SilkS")
		)
		(fp_line
			(start 0.7874 0.4064)
			(end -0.7874 0.4064)
			(stroke
				(width 0.1524)
				(type default)
			)
			(layer "F.SilkS")
		)
		(fp_line
			(start -0.67945 -0.305054)
			(end -0.12065 -0.305054)
			(stroke
				(width 0.1)
				(type default)
			)
			(layer "F.Fab")
		)
		(fp_line
			(start -0.67945 0.3048)
			(end -0.67945 -0.305054)
			(stroke
				(width 0.1)
				(type default)
			)
			(layer "F.Fab")
		)
		(fp_line
			(start -0.12065 -0.305054)
			(end -0.12065 -0.2794)
			(stroke
				(width 0.1)
				(type default)
			)
			(layer "F.Fab")
		)
		(fp_line
			(start -0.12065 -0.2794)
			(end 0.12065 -0.2794)
			(stroke
				(width 0.1)
				(type default)
			)
			(layer "F.Fab")
		)
		(fp_line
			(start -0.12065 0.2794)
			(end -0.12065 0.3048)
			(stroke
				(width 0.1)
				(type default)
			)
			(layer "F.Fab")
		)
		(fp_line
			(start -0.12065 0.3048)
			(end -0.67945 0.3048)
			(stroke
				(width 0.1)
				(type default)
			)
			(layer "F.Fab")
		)
		(fp_line
			(start 0.120396 0.2794)
			(end -0.12065 0.2794)
			(stroke
				(width 0.1)
				(type default)
			)
			(layer "F.Fab")
		)
		(fp_line
			(start 0.120396 0.3048)
			(end 0.120396 0.2794)
			(stroke
				(width 0.1)
				(type default)
			)
			(layer "F.Fab")
		)
		(fp_line
			(start 0.12065 -0.3048)
			(end 0.67945 -0.3048)
			(stroke
				(width 0.1)
				(type default)
			)
			(layer "F.Fab")
		)
		(fp_line
			(start 0.12065 -0.2794)
			(end 0.12065 -0.3048)
			(stroke
				(width 0.1)
				(type default)
			)
			(layer "F.Fab")
		)
		(fp_line
			(start 0.67945 -0.3048)
			(end 0.67945 0.3048)
			(stroke
				(width 0.1)
				(type default)
			)
			(layer "F.Fab")
		)
		(fp_line
			(start 0.67945 0.3048)
			(end 0.120396 0.3048)
			(stroke
				(width 0.1)
				(type default)
			)
			(layer "F.Fab")
		)
		(pad "1" smd circle
			(at -0.40005 0)
			(size 0 0)
			(layers "F.Cu" "F.Mask" "F.Paste")
			(net "RST_RT_CPU0_P3_PERST_R2_N")
		)
		(pad "2" smd circle
			(at 0.40005 0)
			(size 0 0)
			(layers "F.Cu" "F.Mask" "F.Paste")
			(net "RST_RT_CPU0_P3_PERST_R_N")
		)
	)
)
